#ISCELL
  pure_quanta quanta_title_block_c *
  *
#ISCELL
  pure_quanta_power cad_note *
  *
#CELL
  pure_quanta genoa_sp5 *
  page15_i159
#ISCELL
  mstr_standard offpage *
  page15_i160
#ISCELL
  mstr_standard offpage *
  page15_i161
#ISCELL
  mstr_standard tap *
  page15_i162
#ISCELL
  mstr_standard tap *
  page15_i163
#ISCELL
  mstr_standard tap *
  page15_i164
#ISCELL
  mstr_standard tap *
  page15_i165
#ISCELL
  mstr_standard tap *
  page15_i166
#ISCELL
  mstr_standard tap *
  page15_i167
#ISCELL
  mstr_standard tap *
  page15_i168
#ISCELL
  mstr_standard tap *
  page15_i169
#ISCELL
  mstr_standard tap *
  page15_i170
#ISCELL
  mstr_standard tap *
  page15_i171
#ISCELL
  mstr_standard tap *
  page15_i172
#ISCELL
  mstr_standard tap *
  page15_i173
#ISCELL
  mstr_standard tap *
  page15_i174
#ISCELL
  mstr_standard tap *
  page15_i175
#ISCELL
  mstr_standard tap *
  page15_i176
#ISCELL
  mstr_standard tap *
  page15_i177
#ISCELL
  mstr_standard tap *
  page15_i178
#ISCELL
  mstr_standard tap *
  page15_i179
#ISCELL
  mstr_standard tap *
  page15_i180
#ISCELL
  mstr_standard tap *
  page15_i181
#ISCELL
  mstr_standard tap *
  page15_i182
#ISCELL
  mstr_standard tap *
  page15_i183
#ISCELL
  mstr_standard tap *
  page15_i184
#ISCELL
  mstr_standard tap *
  page15_i185
#ISCELL
  mstr_standard tap *
  page15_i186
#ISCELL
  mstr_standard tap *
  page15_i187
#ISCELL
  mstr_standard tap *
  page15_i188
#ISCELL
  mstr_standard tap *
  page15_i189
#ISCELL
  mstr_standard tap *
  page15_i190
#ISCELL
  mstr_standard tap *
  page15_i191
#ISCELL
  mstr_standard tap *
  page15_i192
#ISCELL
  mstr_standard tap *
  page15_i193
#ISCELL
  mstr_standard tap *
  page15_i194
#ISCELL
  mstr_standard tap *
  page15_i195
#ISCELL
  mstr_standard offpage *
  page15_i196
#ISCELL
  mstr_standard tap *
  page15_i197
#ISCELL
  mstr_standard tap *
  page15_i198
#ISCELL
  mstr_standard tap *
  page15_i199
#ISCELL
  mstr_standard tap *
  page15_i200
#ISCELL
  mstr_standard tap *
  page15_i201
#ISCELL
  mstr_standard tap *
  page15_i202
#ISCELL
  mstr_standard tap *
  page15_i203
#ISCELL
  mstr_standard tap *
  page15_i204
#ISCELL
  mstr_standard tap *
  page15_i205
#ISCELL
  mstr_standard tap *
  page15_i206
#ISCELL
  mstr_standard tap *
  page15_i207
#ISCELL
  mstr_standard tap *
  page15_i208
#ISCELL
  mstr_standard tap *
  page15_i209
#ISCELL
  mstr_standard tap *
  page15_i210
#ISCELL
  mstr_standard tap *
  page15_i211
#ISCELL
  mstr_standard tap *
  page15_i212
#ISCELL
  mstr_standard tap *
  page15_i213
#ISCELL
  mstr_standard tap *
  page15_i214
#ISCELL
  mstr_standard tap *
  page15_i215
#ISCELL
  mstr_standard tap *
  page15_i216
#ISCELL
  mstr_standard tap *
  page15_i217
#ISCELL
  mstr_standard tap *
  page15_i218
#ISCELL
  mstr_standard tap *
  page15_i219
#ISCELL
  mstr_standard tap *
  page15_i220
#ISCELL
  mstr_standard tap *
  page15_i221
#ISCELL
  mstr_standard tap *
  page15_i222
#ISCELL
  mstr_standard tap *
  page15_i223
#ISCELL
  mstr_standard tap *
  page15_i224
#ISCELL
  mstr_standard tap *
  page15_i225
#ISCELL
  mstr_standard tap *
  page15_i226
#ISCELL
  mstr_standard tap *
  page15_i227
#ISCELL
  mstr_standard tap *
  page15_i228
#ISCELL
  mstr_standard tap *
  page15_i229
#ISCELL
  mstr_standard tap *
  page15_i230
#ISCELL
  mstr_standard tap *
  page15_i231
#ISCELL
  mstr_standard tap *
  page15_i232
#ISCELL
  mstr_standard tap *
  page15_i233
#ISCELL
  mstr_standard offpage *
  page15_i234
#ISCELL
  mstr_standard tap *
  page15_i235
#ISCELL
  mstr_standard tap *
  page15_i236
#ISCELL
  mstr_standard tap *
  page15_i237
#ISCELL
  mstr_standard tap *
  page15_i238
#ISCELL
  mstr_standard tap *
  page15_i239
#ISCELL
  mstr_standard tap *
  page15_i240
#ISCELL
  mstr_standard tap *
  page15_i241
#ISCELL
  mstr_standard tap *
  page15_i242
#ISCELL
  mstr_standard tap *
  page15_i243
#ISCELL
  mstr_standard tap *
  page15_i244
#ISCELL
  mstr_standard tap *
  page15_i245
#ISCELL
  mstr_standard tap *
  page15_i246
#ISCELL
  mstr_standard tap *
  page15_i247
#ISCELL
  mstr_standard tap *
  page15_i248
#ISCELL
  mstr_standard tap *
  page15_i249
#ISCELL
  mstr_standard tap *
  page15_i250
#ISCELL
  mstr_standard tap *
  page15_i251
#ISCELL
  mstr_standard tap *
  page15_i252
#ISCELL
  mstr_standard tap *
  page15_i253
#ISCELL
  mstr_standard tap *
  page15_i254
#ISCELL
  mstr_standard tap *
  page15_i255
#ISCELL
  mstr_standard tap *
  page15_i256
#ISCELL
  mstr_standard tap *
  page15_i257
#ISCELL
  mstr_standard tap *
  page15_i258
#ISCELL
  mstr_standard tap *
  page15_i259
#ISCELL
  mstr_standard tap *
  page15_i260
#ISCELL
  mstr_standard tap *
  page15_i261
#ISCELL
  mstr_standard tap *
  page15_i262
#ISCELL
  mstr_standard tap *
  page15_i263
#ISCELL
  mstr_standard tap *
  page15_i264
#ISCELL
  mstr_standard tap *
  page15_i265
#ISCELL
  mstr_standard tap *
  page15_i266
#ISCELL
  mstr_standard tap *
  page15_i267
#ISCELL
  mstr_standard tap *
  page15_i268
#ISCELL
  mstr_standard tap *
  page15_i269
#ISCELL
  mstr_standard tap *
  page15_i270
#ISCELL
  mstr_standard tap *
  page15_i271
#ISCELL
  mstr_standard tap *
  page15_i272
#ISCELL
  mstr_standard tap *
  page15_i273
#ISCELL
  mstr_standard tap *
  page15_i274
#ISCELL
  mstr_standard tap *
  page15_i275
#ISCELL
  mstr_standard tap *
  page15_i276
#ISCELL
  mstr_standard tap *
  page15_i277
#ISCELL
  mstr_standard tap *
  page15_i278
#ISCELL
  mstr_standard tap *
  page15_i279
#ISCELL
  mstr_standard tap *
  page15_i280
#ISCELL
  standard offpage *
  page15_i281
#ISCELL
  standard offpage *
  page15_i282
#ISCELL
  standard offpage *
  page15_i283
#ISCELL
  standard offpage *
  page15_i284
#ISCELL
  mstr_standard tap *
  page15_i285
#ISCELL
  mstr_standard tap *
  page15_i286
#ISCELL
  mstr_standard tap *
  page15_i287
#ISCELL
  mstr_standard tap *
  page15_i288
#ISCELL
  mstr_standard tap *
  page15_i289
#ISCELL
  mstr_standard tap *
  page15_i290
#ISCELL
  mstr_standard tap *
  page15_i291
#ISCELL
  mstr_standard tap *
  page15_i292
#ISCELL
  mstr_standard tap *
  page15_i293
#ISCELL
  mstr_standard tap *
  page15_i294
#ISCELL
  mstr_standard tap *
  page15_i295
#ISCELL
  mstr_standard tap *
  page15_i296
#ISCELL
  mstr_standard tap *
  page15_i297
#ISCELL
  mstr_standard tap *
  page15_i298
#ISCELL
  mstr_standard tap *
  page15_i299
#ISCELL
  mstr_standard tap *
  page15_i300
#ISCELL
  mstr_standard tap *
  page15_i301
#ISCELL
  standard offpage *
  page15_i302
#ISCELL
  standard offpage *
  page15_i303
#ISCELL
  standard offpage *
  page15_i304
#ISCELL
  standard offpage *
  page15_i305
#ISCELL
  standard offpage *
  page15_i306
#ISCELL
  standard offpage *
  page15_i307
#ISCELL
  standard offpage *
  page15_i308
#ISCELL
  standard offpage *
  page15_i309
#ISCELL
  mstr_standard offpage *
  page15_i310
#ISCELL
  standard offpage *
  page15_i311
#ISCELL
  standard offpage *
  page15_i312
#ISCELL
  standard offpage *
  page15_i313
#CELL
  pure_quanta q_res *
  page15_i314
#ISCELL
  mstr_standard offpage *
  page15_i315
#ISCELL
  standard offpage *
  page15_i316
